# T6G (Grand Teton) — schematic netlist excerpt (pin names and nets, part order shuffled) for the footprints in the layout excerpt that follows; sources: Cadence DE-HDL packaged netlist, KiCad conversion of 04192023_DAF0TMB3IC0_F0TG_MB_C_brd_V02_OCP.brd

C215  Q_CAP  8.2PF 50V 0.1P NP0  pkg C0402  page 28 : A = XTAL_CPU0_X32K_X1 ; B = GND
R4604  Q_RES  4.7K 5% CHIP  pkg 0402LF  page 253 : A = P3V3_AUX ; B = PWRGD_PS_PWROK_PLD_N

(kicad_pcb
	(version 20260206)
	(generator "pcbnew")
	(generator_version "10.0")
	(general
		(thickness 1.6)
		(legacy_teardrops no)
	)
	(paper "A4")
	(title_block
		(title "04192023_DAF0TMB3IC0_F0TG_MB_C_brd_V02_OCP.brd")
		(comment 1 "Grand Teton / footprints 7858-7859 of 8354")
	)
	(layers
		(0 "F.Cu" signal "TOP")
		(4 "In1.Cu" signal "GND")
		(6 "In2.Cu" signal "IN1")
		(8 "In3.Cu" signal "GND1")
		(10 "In4.Cu" signal "IN2")
		(12 "In5.Cu" signal "GND2")
		(14 "In6.Cu" signal "IN3")
		(16 "In7.Cu" signal "GND3")
		(18 "In8.Cu" signal "VCC")
		(20 "In9.Cu" signal "VCC1")
		(22 "In10.Cu" signal "GND4")
		(24 "In11.Cu" signal "IN4")
		(26 "In12.Cu" signal "GND5")
		(28 "In13.Cu" signal "IN5")
		(30 "In14.Cu" signal "GND6")
		(32 "In15.Cu" signal "IN6")
		(34 "In16.Cu" signal "GND7")
		(2 "B.Cu" signal "BOTTOM")
		(9 "F.Adhes" user "F.Adhesive")
		(11 "B.Adhes" user "B.Adhesive")
		(13 "F.Paste" user "Package Geometry/Pastemask Top")
		(15 "B.Paste" user "Package Geometry/Pastemask Bottom")
		(5 "F.SilkS" user "Ref Des/Silkscreen Top")
		(7 "B.SilkS" user "Ref Des/Silkscreen Bottom")
		(1 "F.Mask" user "Board Geometry/Soldermask Top")
		(3 "B.Mask" user "Board Geometry/Soldermask Bottom")
		(17 "Dwgs.User" user "User.Drawings")
		(19 "Cmts.User" user "User.Comments")
		(21 "Eco1.User" user "User.Eco1")
		(23 "Eco2.User" user "User.Eco2")
		(25 "Edge.Cuts" user "Board Geometry/Outline")
		(27 "Margin" user)
		(31 "F.CrtYd" user "Package Geometry/Place Bound Top")
		(29 "B.CrtYd" user "Package Geometry/Place Bound Bottom")
		(35 "F.Fab" user "Ref Des/Assembly Top")
		(33 "B.Fab" user "Ref Des/Assembly Bottom")
	)
	(footprint ""
		(layer "B.Cu")
		(at 316.93739 -76.639928 90)
		(property "Reference" "R4604"
			(at 0 0 90)
			(layer "B.SilkS")
			(hide yes)
			(effects
				(font
					(size 1.27 1.27)
				)
				(justify mirror)
			)
		)
		(property "Value" ""
			(at 0 0 90)
			(layer "B.Fab")
			(effects
				(font
					(size 1.27 1.27)
				)
				(justify mirror)
			)
		)
		(duplicate_pad_numbers_are_jumpers no)
		(fp_line
			(start 0.7874 -0.4064)
			(end -0.7874 -0.4064)
			(stroke
				(width 0.1524)
				(type default)
			)
			(layer "B.SilkS")
		)
		(fp_line
			(start -0.7874 -0.4064)
			(end -0.7874 0.4064)
			(stroke
				(width 0.1524)
				(type default)
			)
			(layer "B.SilkS")
		)
		(fp_line
			(start 0.7874 0.4064)
			(end 0.7874 -0.4064)
			(stroke
				(width 0.1524)
				(type default)
			)
			(layer "B.SilkS")
		)
		(fp_line
			(start -0.7874 0.4064)
			(end 0.7874 0.4064)
			(stroke
				(width 0.1524)
				(type default)
			)
			(layer "B.SilkS")
		)
		(fp_line
			(start 0.67945 -0.305054)
			(end 0.12065 -0.305054)
			(stroke
				(width 0.1)
				(type default)
			)
			(layer "B.Fab")
		)
		(fp_line
			(start 0.12065 -0.305054)
			(end 0.12065 -0.2794)
			(stroke
				(width 0.1)
				(type default)
			)
			(layer "B.Fab")
		)
		(fp_line
			(start -0.12065 -0.3048)
			(end -0.67945 -0.3048)
			(stroke
				(width 0.1)
				(type default)
			)
			(layer "B.Fab")
		)
		(fp_line
			(start -0.67945 -0.3048)
			(end -0.67945 0.3048)
			(stroke
				(width 0.1)
				(type default)
			)
			(layer "B.Fab")
		)
		(fp_line
			(start 0.12065 -0.2794)
			(end -0.12065 -0.2794)
			(stroke
				(width 0.1)
				(type default)
			)
			(layer "B.Fab")
		)
		(fp_line
			(start -0.12065 -0.2794)
			(end -0.12065 -0.3048)
			(stroke
				(width 0.1)
				(type default)
			)
			(layer "B.Fab")
		)
		(fp_line
			(start 0.12065 0.2794)
			(end 0.12065 0.3048)
			(stroke
				(width 0.1)
				(type default)
			)
			(layer "B.Fab")
		)
		(fp_line
			(start -0.120396 0.2794)
			(end 0.12065 0.2794)
			(stroke
				(width 0.1)
				(type default)
			)
			(layer "B.Fab")
		)
		(fp_line
			(start 0.67945 0.3048)
			(end 0.67945 -0.305054)
			(stroke
				(width 0.1)
				(type default)
			)
			(layer "B.Fab")
		)
		(fp_line
			(start 0.12065 0.3048)
			(end 0.67945 0.3048)
			(stroke
				(width 0.1)
				(type default)
			)
			(layer "B.Fab")
		)
		(fp_line
			(start -0.120396 0.3048)
			(end -0.120396 0.2794)
			(stroke
				(width 0.1)
				(type default)
			)
			(layer "B.Fab")
		)
		(fp_line
			(start -0.67945 0.3048)
			(end -0.120396 0.3048)
			(stroke
				(width 0.1)
				(type default)
			)
			(layer "B.Fab")
		)
		(pad "1" smd circle
			(at 0.40005 0 270)
			(size 0 0)
			(layers "B.Cu" "B.Mask" "B.Paste")
			(net "P3V3_AUX")
		)
		(pad "2" smd circle
			(at -0.40005 0 270)
			(size 0 0)
			(layers "B.Cu" "B.Mask" "B.Paste")
			(net "PWRGD_PS_PWROK_PLD_N")
		)
	)
	(footprint ""
		(layer "B.Cu")
		(at 400.761962 -314.925964)
		(property "Reference" "C215"
			(at 0 0 0)
			(layer "B.SilkS")
			(hide yes)
			(effects
				(font
					(size 1.27 1.27)
				)
				(justify mirror)
			)
		)
		(property "Value" ""
			(at 0 0 0)
			(layer "B.Fab")
			(effects
				(font
					(size 1.27 1.27)
				)
				(justify mirror)
			)
		)
		(duplicate_pad_numbers_are_jumpers no)
		(fp_line
			(start -0.7874 -0.4064)
			(end -0.7874 0.4064)
			(stroke
				(width 0.1524)
				(type default)
			)
			(layer "B.SilkS")
		)
		(fp_line
			(start -0.7874 0.4064)
			(end 0.7874 0.4064)
			(stroke
				(width 0.1524)
				(type default)
			)
			(layer "B.SilkS")
		)
		(fp_line
			(start 0.7874 -0.4064)
			(end -0.7874 -0.4064)
			(stroke
				(width 0.1524)
				(type default)
			)
			(layer "B.SilkS")
		)
		(fp_line
			(start 0.7874 0.4064)
			(end 0.7874 -0.4064)
			(stroke
				(width 0.1524)
				(type default)
			)
			(layer "B.SilkS")
		)
		(fp_line
			(start -0.67945 -0.3048)
			(end -0.67945 0.3048)
			(stroke
				(width 0.1)
				(type default)
			)
			(layer "B.Fab")
		)
		(fp_line
			(start -0.67945 0.3048)
			(end -0.120396 0.3048)
			(stroke
				(width 0.1)
				(type default)
			)
			(layer "B.Fab")
		)
		(fp_line
			(start -0.12065 -0.3048)
			(end -0.67945 -0.3048)
			(stroke
				(width 0.1)
				(type default)
			)
			(layer "B.Fab")
		)
		(fp_line
			(start -0.12065 -0.2794)
			(end -0.12065 -0.3048)
			(stroke
				(width 0.1)
				(type default)
			)
			(layer "B.Fab")
		)
		(fp_line
			(start -0.120396 0.2794)
			(end 0.12065 0.2794)
			(stroke
				(width 0.1)
				(type default)
			)
			(layer "B.Fab")
		)
		(fp_line
			(start -0.120396 0.3048)
			(end -0.120396 0.2794)
			(stroke
				(width 0.1)
				(type default)
			)
			(layer "B.Fab")
		)
		(fp_line
			(start 0.12065 -0.305054)
			(end 0.12065 -0.2794)
			(stroke
				(width 0.1)
				(type default)
			)
			(layer "B.Fab")
		)
		(fp_line
			(start 0.12065 -0.2794)
			(end -0.12065 -0.2794)
			(stroke
				(width 0.1)
				(type default)
			)
			(layer "B.Fab")
		)
		(fp_line
			(start 0.12065 0.2794)
			(end 0.12065 0.3048)
			(stroke
				(width 0.1)
				(type default)
			)
			(layer "B.Fab")
		)
		(fp_line
			(start 0.12065 0.3048)
			(end 0.67945 0.3048)
			(stroke
				(width 0.1)
				(type default)
			)
			(layer "B.Fab")
		)
		(fp_line
			(start 0.67945 -0.305054)
			(end 0.12065 -0.305054)
			(stroke
				(width 0.1)
				(type default)
			)
			(layer "B.Fab")
		)
		(fp_line
			(start 0.67945 0.3048)
			(end 0.67945 -0.305054)
			(stroke
				(width 0.1)
				(type default)
			)
			(layer "B.Fab")
		)
		(pad "1" smd circle
			(at 0.40005 0 180)
			(size 0 0)
			(layers "B.Cu" "B.Mask" "B.Paste")
			(net "XTAL_CPU0_X32K_X1")
		)
		(pad "2" smd circle
			(at -0.40005 0 180)
			(size 0 0)
			(layers "B.Cu" "B.Mask" "B.Paste")
			(net "GND")
		)
	)
)
